(kicad_pcb
	(version 20260206)
	(generator "pcbnew")
	(generator_version "10.0")
	(general
		(thickness 1.6)
		(legacy_teardrops no)
	)
	(paper "A4")
	(title_block
		(title "dpb — 14545-sa.0730WZS0815.brd")
		(comment 1 "Honey Badger (Wiwynn) / footprints 258-265 of 1066")
	)
	(layers
		(0 "F.Cu" signal "TOP")
		(4 "In1.Cu" signal "L2GND")
		(6 "In2.Cu" signal "L3")
		(8 "In3.Cu" signal "L4VCC")
		(10 "In4.Cu" signal "L5VCC")
		(12 "In5.Cu" signal "L6")
		(14 "In6.Cu" signal "L7GND")
		(2 "B.Cu" signal "BOTTOM")
		(9 "F.Adhes" user "F.Adhesive")
		(11 "B.Adhes" user "B.Adhesive")
		(13 "F.Paste" user "Package Geometry/Pastemask Top")
		(15 "B.Paste" user "Package Geometry/Pastemask Bottom")
		(5 "F.SilkS" user "Ref Des/Silkscreen Top")
		(7 "B.SilkS" user "Ref Des/Silkscreen Bottom")
		(1 "F.Mask" user "Board Geometry/Soldermask Top")
		(3 "B.Mask" user "Board Geometry/Soldermask Bottom")
		(17 "Dwgs.User" user "User.Drawings")
		(19 "Cmts.User" user "User.Comments")
		(21 "Eco1.User" user "User.Eco1")
		(23 "Eco2.User" user "User.Eco2")
		(25 "Edge.Cuts" user "Board Geometry/Outline")
		(27 "Margin" user)
		(31 "F.CrtYd" user "Package Geometry/Place Bound Top")
		(29 "B.CrtYd" user "Package Geometry/Place Bound Bottom")
		(35 "F.Fab" user "Ref Des/Assembly Top")
		(33 "B.Fab" user "Ref Des/Assembly Bottom")
	)
	(footprint ""
		(layer "F.Cu")
		(at 221.444058 -350.468184 90)
		(property "Reference" "R115"
			(at 0 0 90)
			(layer "F.SilkS")
			(hide yes)
			(effects
				(font
					(size 1.27 1.27)
				)
			)
		)
		(property "Value" "402R2F-GP"
			(at 0.064008 -3.993896 90)
			(unlocked yes)
			(layer "F.Fab")
			(hide yes)
			(effects
				(font
					(size 1.016 1.016)
					(thickness 0.1524)
				)
			)
		)
		(property "Device Type" "R402H16"
			(at 0.064008 -5.517896 90)
			(unlocked yes)
			(layer "F.Fab")
			(hide yes)
			(effects
				(font
					(size 1.016 1.016)
					(thickness 0.1524)
				)
			)
		)
		(duplicate_pad_numbers_are_jumpers no)
		(fp_line
			(start 0.508 -0.9398)
			(end -0.508 -0.9398)
			(stroke
				(width 0.1524)
				(type default)
			)
			(layer "F.SilkS")
		)
		(fp_line
			(start -0.508 -0.9398)
			(end -0.508 0.9398)
			(stroke
				(width 0.1524)
				(type default)
			)
			(layer "F.SilkS")
		)
		(fp_rect
			(start -0.508 0.9398)
			(end 0.508 -0.9398)
			(stroke
				(width 0)
				(type default)
			)
			(fill no)
			(layer "F.CrtYd")
		)
		(fp_rect
			(start -0.508 0.9398)
			(end 0.508 -0.9398)
			(stroke
				(width 0)
				(type default)
			)
			(fill no)
			(layer "F.Fab")
		)
		(pad "1" smd custom
			(at 0 -0.4445 90)
			(size 0.1397 0.1397)
			(layers "F.Cu" "F.Mask" "F.Paste")
			(net "P5VA_HDD1_LED")
			(options
				(clearance outline)
				(anchor circle)
			)
			(primitives
				(gr_poly
					(pts
						(arc
							(start -0.1778 -0.2794)
							(mid -0.249642 -0.249642)
							(end -0.2794 -0.1778)
						)
						(arc
							(start -0.2794 0.1778)
							(mid -0.249642 0.249642)
							(end -0.1778 0.2794)
						)
						(arc
							(start 0.1778 0.2794)
							(mid 0.249642 0.249642)
							(end 0.2794 0.1778)
						)
						(arc
							(start 0.2794 -0.1778)
							(mid 0.249642 -0.249642)
							(end 0.1778 -0.2794)
						)
					)
					(width 0)
					(fill yes)
				)
			)
		)
		(pad "2" smd custom
			(at 0 0.4445 90)
			(size 0.1397 0.1397)
			(layers "F.Cu" "F.Mask" "F.Paste")
			(net "DRV_ACT_1")
			(options
				(clearance outline)
				(anchor circle)
			)
			(primitives
				(gr_poly
					(pts
						(arc
							(start -0.1778 -0.2794)
							(mid -0.249642 -0.249642)
							(end -0.2794 -0.1778)
						)
						(arc
							(start -0.2794 0.1778)
							(mid -0.249642 0.249642)
							(end -0.1778 0.2794)
						)
						(arc
							(start 0.1778 0.2794)
							(mid 0.249642 0.249642)
							(end 0.2794 0.1778)
						)
						(arc
							(start 0.2794 -0.1778)
							(mid 0.249642 -0.249642)
							(end 0.1778 -0.2794)
						)
					)
					(width 0)
					(fill yes)
				)
			)
		)
	)
	(footprint ""
		(layer "F.Cu")
		(at 39.572946 -138.2395 90)
		(property "Reference" "R319"
			(at 0 0 90)
			(layer "F.SilkS")
			(hide yes)
			(effects
				(font
					(size 1.27 1.27)
				)
			)
		)
		(property "Value" "0R2J-2-GP"
			(at 0.064008 -3.993896 90)
			(unlocked yes)
			(layer "F.Fab")
			(hide yes)
			(effects
				(font
					(size 1.016 1.016)
					(thickness 0.1524)
				)
			)
		)
		(property "Device Type" "R402H16"
			(at 0.064008 -5.517896 90)
			(unlocked yes)
			(layer "F.Fab")
			(hide yes)
			(effects
				(font
					(size 1.016 1.016)
					(thickness 0.1524)
				)
			)
		)
		(duplicate_pad_numbers_are_jumpers no)
		(fp_line
			(start 0.508 -0.9398)
			(end -0.508 -0.9398)
			(stroke
				(width 0.1524)
				(type default)
			)
			(layer "F.SilkS")
		)
		(fp_line
			(start -0.508 -0.9398)
			(end -0.508 0.9398)
			(stroke
				(width 0.1524)
				(type default)
			)
			(layer "F.SilkS")
		)
		(fp_rect
			(start -0.508 0.9398)
			(end 0.508 -0.9398)
			(stroke
				(width 0)
				(type default)
			)
			(fill no)
			(layer "F.CrtYd")
		)
		(fp_rect
			(start -0.508 0.9398)
			(end 0.508 -0.9398)
			(stroke
				(width 0)
				(type default)
			)
			(fill no)
			(layer "F.Fab")
		)
		(pad "1" smd custom
			(at 0 -0.4445 90)
			(size 0.1397 0.1397)
			(layers "F.Cu" "F.Mask" "F.Paste")
			(net "I2C_B_SCL")
			(options
				(clearance outline)
				(anchor circle)
			)
			(primitives
				(gr_poly
					(pts
						(arc
							(start -0.1778 -0.2794)
							(mid -0.249642 -0.249642)
							(end -0.2794 -0.1778)
						)
						(arc
							(start -0.2794 0.1778)
							(mid -0.249642 0.249642)
							(end -0.1778 0.2794)
						)
						(arc
							(start 0.1778 0.2794)
							(mid 0.249642 0.249642)
							(end 0.2794 0.1778)
						)
						(arc
							(start 0.2794 -0.1778)
							(mid 0.249642 -0.249642)
							(end 0.1778 -0.2794)
						)
					)
					(width 0)
					(fill yes)
				)
			)
		)
		(pad "2" smd custom
			(at 0 0.4445 90)
			(size 0.1397 0.1397)
			(layers "F.Cu" "F.Mask" "F.Paste")
			(net "TMP2_SCL")
			(options
				(clearance outline)
				(anchor circle)
			)
			(primitives
				(gr_poly
					(pts
						(arc
							(start -0.1778 -0.2794)
							(mid -0.249642 -0.249642)
							(end -0.2794 -0.1778)
						)
						(arc
							(start -0.2794 0.1778)
							(mid -0.249642 0.249642)
							(end -0.1778 0.2794)
						)
						(arc
							(start 0.1778 0.2794)
							(mid 0.249642 0.249642)
							(end 0.2794 0.1778)
						)
						(arc
							(start 0.2794 -0.1778)
							(mid 0.249642 -0.249642)
							(end 0.1778 -0.2794)
						)
					)
					(width 0)
					(fill yes)
				)
			)
		)
	)
	(footprint ""
		(layer "F.Cu")
		(at 43.052746 -226.215702)
		(property "Reference" "C299"
			(at 0 0 0)
			(layer "F.SilkS")
			(hide yes)
			(effects
				(font
					(size 1.27 1.27)
				)
			)
		)
		(property "Value" "SC10U16V6KX-2GP"
			(at -0.0762 -5.1308 0)
			(unlocked yes)
			(layer "F.Fab")
			(hide yes)
			(effects
				(font
					(size 1.016 1.016)
					(thickness 0.1524)
				)
			)
		)
		(property "Device Type" "C1206H71"
			(at -0.127 -6.6548 0)
			(unlocked yes)
			(layer "F.Fab")
			(hide yes)
			(effects
				(font
					(size 1.016 1.016)
					(thickness 0.1524)
				)
			)
		)
		(duplicate_pad_numbers_are_jumpers no)
		(fp_line
			(start -1.016 -2.2352)
			(end 1.016 -2.2352)
			(stroke
				(width 0.1524)
				(type default)
			)
			(layer "F.SilkS")
		)
		(fp_line
			(start -1.016 -0.8382)
			(end -1.016 -2.2352)
			(stroke
				(width 0.1524)
				(type default)
			)
			(layer "F.SilkS")
		)
		(fp_line
			(start -1.016 2.2352)
			(end -1.016 0.8382)
			(stroke
				(width 0.1524)
				(type default)
			)
			(layer "F.SilkS")
		)
		(fp_line
			(start 1.016 -2.2352)
			(end 1.016 -0.8382)
			(stroke
				(width 0.1524)
				(type default)
			)
			(layer "F.SilkS")
		)
		(fp_line
			(start 1.016 0.8382)
			(end 1.016 2.2352)
			(stroke
				(width 0.1524)
				(type default)
			)
			(layer "F.SilkS")
		)
		(fp_line
			(start 1.016 2.2352)
			(end -1.016 2.2352)
			(stroke
				(width 0.1524)
				(type default)
			)
			(layer "F.SilkS")
		)
		(fp_rect
			(start -1.0922 2.3114)
			(end 1.0922 -2.3114)
			(stroke
				(width 0)
				(type default)
			)
			(fill no)
			(layer "F.CrtYd")
		)
		(fp_poly
			(pts
				(xy 1.0922 -2.3114) (xy 1.0922 2.3114) (xy -1.0922 2.3114) (xy -1.0922 -2.3114)
			)
			(stroke
				(width 0)
				(type default)
			)
			(fill no)
			(layer "F.Fab")
		)
		(pad "1" smd rect
			(at 0 -1.397)
			(size 1.651 1.27)
			(layers "F.Cu" "F.Mask" "F.Paste")
			(net "P5V_HDD12")
		)
		(pad "2" smd rect
			(at 0 1.397)
			(size 1.651 1.27)
			(layers "F.Cu" "F.Mask" "F.Paste")
			(net "GND")
		)
	)
	(footprint ""
		(layer "F.Cu")
		(at 26.034746 -36.8427 90)
		(property "Reference" "C326"
			(at 0 0 90)
			(layer "F.SilkS")
			(hide yes)
			(effects
				(font
					(size 1.27 1.27)
				)
			)
		)
		(property "Value" "SCD01U50V2KX-1GP"
			(at 1.1811 -2.7051 90)
			(unlocked yes)
			(layer "F.Fab")
			(hide yes)
			(effects
				(font
					(size 1.016 1.016)
					(thickness 0.1524)
				)
			)
		)
		(property "Device Type" "C402H22"
			(at 1.1811 -4.2291 90)
			(unlocked yes)
			(layer "F.Fab")
			(hide yes)
			(effects
				(font
					(size 1.016 1.016)
					(thickness 0.1524)
				)
			)
		)
		(duplicate_pad_numbers_are_jumpers no)
		(fp_rect
			(start -0.4318 0.9525)
			(end 0.4318 -0.9525)
			(stroke
				(width 0)
				(type default)
			)
			(fill no)
			(layer "F.CrtYd")
		)
		(fp_rect
			(start -0.4318 0.9525)
			(end 0.4318 -0.9525)
			(stroke
				(width 0)
				(type default)
			)
			(fill no)
			(layer "F.Fab")
		)
		(pad "1" smd custom
			(at 0 -0.4445 90)
			(size 0.1524 0.1524)
			(layers "F.Cu" "F.Mask" "F.Paste")
			(net "SAS2X28_DRIVE_RX_N_A14")
			(options
				(clearance outline)
				(anchor circle)
			)
			(primitives
				(gr_poly
					(pts
						(arc
							(start 0.3048 -0.2032)
							(mid 0.275042 -0.275042)
							(end 0.2032 -0.3048)
						)
						(arc
							(start -0.2032 -0.3048)
							(mid -0.275042 -0.275042)
							(end -0.3048 -0.2032)
						)
						(arc
							(start -0.3048 0.2032)
							(mid -0.275042 0.275042)
							(end -0.2032 0.3048)
						)
						(arc
							(start 0.2032 0.3048)
							(mid 0.275042 0.275042)
							(end 0.3048 0.2032)
						)
					)
					(width 0)
					(fill yes)
				)
			)
		)
		(pad "2" smd custom
			(at 0 0.4445 90)
			(size 0.1524 0.1524)
			(layers "F.Cu" "F.Mask" "F.Paste")
			(net "SAS2X28_A_HDD14_RX_-")
			(options
				(clearance outline)
				(anchor circle)
			)
			(primitives
				(gr_poly
					(pts
						(arc
							(start 0.3048 -0.2032)
							(mid 0.275042 -0.275042)
							(end 0.2032 -0.3048)
						)
						(arc
							(start -0.2032 -0.3048)
							(mid -0.275042 -0.275042)
							(end -0.3048 -0.2032)
						)
						(arc
							(start -0.3048 0.2032)
							(mid -0.275042 0.275042)
							(end -0.2032 0.3048)
						)
						(arc
							(start 0.2032 0.3048)
							(mid 0.275042 0.275042)
							(end 0.3048 0.2032)
						)
					)
					(width 0)
					(fill yes)
				)
			)
		)
	)
	(footprint ""
		(layer "F.Cu")
		(at 5.079746 -499.5037)
		(property "Reference" "PR38"
			(at 0 0 0)
			(layer "F.SilkS")
			(hide yes)
			(effects
				(font
					(size 1.27 1.27)
				)
			)
		)
		(property "Value" "866KR2F-GP"
			(at 0.064008 -3.993896 0)
			(unlocked yes)
			(layer "F.Fab")
			(hide yes)
			(effects
				(font
					(size 1.016 1.016)
					(thickness 0.1524)
				)
			)
		)
		(property "Device Type" "R402H16"
			(at 0.064008 -5.517896 0)
			(unlocked yes)
			(layer "F.Fab")
			(hide yes)
			(effects
				(font
					(size 1.016 1.016)
					(thickness 0.1524)
				)
			)
		)
		(duplicate_pad_numbers_are_jumpers no)
		(fp_line
			(start -0.508 -0.9398)
			(end -0.508 0.9398)
			(stroke
				(width 0.1524)
				(type default)
			)
			(layer "F.SilkS")
		)
		(fp_line
			(start 0.508 -0.9398)
			(end -0.508 -0.9398)
			(stroke
				(width 0.1524)
				(type default)
			)
			(layer "F.SilkS")
		)
		(fp_rect
			(start -0.508 0.9398)
			(end 0.508 -0.9398)
			(stroke
				(width 0)
				(type default)
			)
			(fill no)
			(layer "F.CrtYd")
		)
		(fp_rect
			(start -0.508 0.9398)
			(end 0.508 -0.9398)
			(stroke
				(width 0)
				(type default)
			)
			(fill no)
			(layer "F.Fab")
		)
		(pad "1" smd custom
			(at 0 -0.4445)
			(size 0.1397 0.1397)
			(layers "F.Cu" "F.Mask" "F.Paste")
			(net "P5VC_VREG")
			(options
				(clearance outline)
				(anchor circle)
			)
			(primitives
				(gr_poly
					(pts
						(arc
							(start -0.1778 -0.2794)
							(mid -0.249642 -0.249642)
							(end -0.2794 -0.1778)
						)
						(arc
							(start -0.2794 0.1778)
							(mid -0.249642 0.249642)
							(end -0.1778 0.2794)
						)
						(arc
							(start 0.1778 0.2794)
							(mid 0.249642 0.249642)
							(end 0.2794 0.1778)
						)
						(arc
							(start 0.2794 -0.1778)
							(mid 0.249642 -0.249642)
							(end 0.1778 -0.2794)
						)
					)
					(width 0)
					(fill yes)
				)
			)
		)
		(pad "2" smd custom
			(at 0 0.4445)
			(size 0.1397 0.1397)
			(layers "F.Cu" "F.Mask" "F.Paste")
			(net "P5VC_RF")
			(options
				(clearance outline)
				(anchor circle)
			)
			(primitives
				(gr_poly
					(pts
						(arc
							(start -0.1778 -0.2794)
							(mid -0.249642 -0.249642)
							(end -0.2794 -0.1778)
						)
						(arc
							(start -0.2794 0.1778)
							(mid -0.249642 0.249642)
							(end -0.1778 0.2794)
						)
						(arc
							(start 0.1778 0.2794)
							(mid 0.249642 0.249642)
							(end 0.2794 0.1778)
						)
						(arc
							(start 0.2794 -0.1778)
							(mid 0.249642 -0.249642)
							(end 0.1778 -0.2794)
						)
					)
					(width 0)
					(fill yes)
				)
			)
		)
	)
	(footprint ""
		(layer "F.Cu")
		(at 252.499622 -37.999924)
		(property "Reference" "H16"
			(at 0 0 0)
			(layer "F.SilkS")
			(hide yes)
			(effects
				(font
					(size 1.27 1.27)
				)
			)
		)
		(property "Value" "HOLE315R140"
			(at 0 -7.5692 0)
			(unlocked yes)
			(layer "F.Fab")
			(hide yes)
			(effects
				(font
					(size 1.016 1.016)
					(thickness 0.1524)
				)
			)
		)
		(property "Device Type" "HOLE315R140"
			(at 0 -9.0932 0)
			(unlocked yes)
			(layer "F.Fab")
			(hide yes)
			(effects
				(font
					(size 1.016 1.016)
					(thickness 0.1524)
				)
			)
		)
		(duplicate_pad_numbers_are_jumpers no)
		(fp_poly
			(pts
				(arc
					(start 4.3053 0)
					(mid -4.3053 0)
					(end 4.3053 0)
				)
			)
			(stroke
				(width 0)
				(type default)
			)
			(fill no)
			(layer "F.CrtYd")
		)
		(fp_poly
			(pts
				(arc
					(start 4.3053 0)
					(mid -4.3053 0)
					(end 4.3053 0)
				)
			)
			(stroke
				(width 0)
				(type default)
			)
			(fill no)
			(layer "F.Fab")
		)
		(pad "1" thru_hole circle
			(at 0.00127 0.00127)
			(size 8.001 8.001)
			(drill 3.556)
			(layers "*.Cu" "*.Mask")
			(remove_unused_layers no)
			(net "GND")
			(clearance -1.7145)
			(thermal_gap 0.3048)
			(padstack
				(mode front_inner_back)
				(layer "Inner"
					(shape circle)
					(size 3.9624 3.9624)
					(clearance 0.3048)
				)
				(layer "B.Cu"
					(shape circle)
					(size 8.001 8.001)
					(clearance -1.7145)
				)
			)
		)
	)
	(footprint ""
		(layer "F.Cu")
		(at 34.544 -134.747 180)
		(property "Reference" "R402"
			(at 0 0 180)
			(layer "F.SilkS")
			(hide yes)
			(effects
				(font
					(size 1.27 1.27)
				)
			)
		)
		(property "Value" "0R2J-2-GP"
			(at 0.064008 -3.993896 180)
			(unlocked yes)
			(layer "F.Fab")
			(hide yes)
			(effects
				(font
					(size 1.016 1.016)
					(thickness 0.1524)
				)
			)
		)
		(property "Device Type" "R402H16"
			(at 0.064008 -5.517896 180)
			(unlocked yes)
			(layer "F.Fab")
			(hide yes)
			(effects
				(font
					(size 1.016 1.016)
					(thickness 0.1524)
				)
			)
		)
		(duplicate_pad_numbers_are_jumpers no)
		(fp_line
			(start 0.508 -0.9398)
			(end -0.508 -0.9398)
			(stroke
				(width 0.1524)
				(type default)
			)
			(layer "F.SilkS")
		)
		(fp_line
			(start -0.508 -0.9398)
			(end -0.508 0.9398)
			(stroke
				(width 0.1524)
				(type default)
			)
			(layer "F.SilkS")
		)
		(fp_rect
			(start -0.508 0.9398)
			(end 0.508 -0.9398)
			(stroke
				(width 0)
				(type default)
			)
			(fill no)
			(layer "F.CrtYd")
		)
		(fp_rect
			(start -0.508 0.9398)
			(end 0.508 -0.9398)
			(stroke
				(width 0)
				(type default)
			)
			(fill no)
			(layer "F.Fab")
		)
		(pad "1" smd custom
			(at 0 -0.4445 180)
			(size 0.1397 0.1397)
			(layers "F.Cu" "F.Mask" "F.Paste")
			(net "HDD_PRSNT_NET13")
			(options
				(clearance outline)
				(anchor circle)
			)
			(primitives
				(gr_poly
					(pts
						(arc
							(start -0.1778 -0.2794)
							(mid -0.249642 -0.249642)
							(end -0.2794 -0.1778)
						)
						(arc
							(start -0.2794 0.1778)
							(mid -0.249642 0.249642)
							(end -0.1778 0.2794)
						)
						(arc
							(start 0.1778 0.2794)
							(mid 0.249642 0.249642)
							(end 0.2794 0.1778)
						)
						(arc
							(start 0.2794 -0.1778)
							(mid 0.249642 -0.249642)
							(end 0.1778 -0.2794)
						)
					)
					(width 0)
					(fill yes)
				)
			)
		)
		(pad "2" smd custom
			(at 0 0.4445 180)
			(size 0.1397 0.1397)
			(layers "F.Cu" "F.Mask" "F.Paste")
			(net "HDD13_LED_B")
			(options
				(clearance outline)
				(anchor circle)
			)
			(primitives
				(gr_poly
					(pts
						(arc
							(start -0.1778 -0.2794)
							(mid -0.249642 -0.249642)
							(end -0.2794 -0.1778)
						)
						(arc
							(start -0.2794 0.1778)
							(mid -0.249642 0.249642)
							(end -0.1778 0.2794)
						)
						(arc
							(start 0.1778 0.2794)
							(mid 0.249642 0.249642)
							(end 0.2794 0.1778)
						)
						(arc
							(start 0.2794 -0.1778)
							(mid 0.249642 -0.249642)
							(end 0.1778 -0.2794)
						)
					)
					(width 0)
					(fill yes)
				)
			)
		)
	)
	(footprint ""
		(layer "F.Cu")
		(at 193.04 -398.272 90)
		(property "Reference" "D16"
			(at 0 0 90)
			(layer "F.SilkS")
			(hide yes)
			(effects
				(font
					(size 1.27 1.27)
				)
			)
		)
		(property "Value" "RB551V30-1-GP"
			(at 0 -6.7818 90)
			(unlocked yes)
			(layer "F.Fab")
			(hide yes)
			(effects
				(font
					(size 1.016 1.016)
					(thickness 0.1524)
				)
			)
		)
		(property "Device Type" "SOD323AKH44"
			(at 0 -8.6868 90)
			(unlocked yes)
			(layer "F.Fab")
			(hide yes)
			(effects
				(font
					(size 1.016 1.016)
					(thickness 0.1524)
				)
			)
		)
		(duplicate_pad_numbers_are_jumpers no)
		(fp_line
			(start 0.889 -1.9304)
			(end 0.889 2.159)
			(stroke
				(width 0.1524)
				(type default)
			)
			(layer "F.SilkS")
		)
		(fp_line
			(start -0.889 -1.9304)
			(end 0.889 -1.9304)
			(stroke
				(width 0.1524)
				(type default)
			)
			(layer "F.SilkS")
		)
		(fp_line
			(start 0.762 2.0574)
			(end -0.762 2.0574)
			(stroke
				(width 0.508)
				(type default)
			)
			(layer "F.SilkS")
		)
		(fp_line
			(start 0.889 2.159)
			(end -0.889 2.159)
			(stroke
				(width 0.1524)
				(type default)
			)
			(layer "F.SilkS")
		)
		(fp_line
			(start -0.889 2.159)
			(end -0.889 -1.9304)
			(stroke
				(width 0.1524)
				(type default)
			)
			(layer "F.SilkS")
		)
		(fp_rect
			(start -1.016 2.3114)
			(end 1.016 -2.0066)
			(stroke
				(width 0)
				(type default)
			)
			(fill no)
			(layer "F.CrtYd")
		)
		(fp_poly
			(pts
				(xy -1.016 -2.0066) (xy 1.016 -2.0066) (xy 1.016 2.3114) (xy -1.016 2.3114)
			)
			(stroke
				(width 0)
				(type default)
			)
			(fill no)
			(layer "F.Fab")
		)
		(pad "A" smd rect
			(at 0 -1.143 90)
			(size 0.5588 1.016)
			(layers "F.Cu" "F.Mask" "F.Paste")
			(net "SW_HDD1_R")
		)
		(pad "K" smd rect
			(at 0 1.143 90)
			(size 0.5588 1.016)
			(layers "F.Cu" "F.Mask" "F.Paste")
			(net "SW_HDD1_N")
		)
	)
)
